FILE_TYPE = CONNECTIVITY;
{Allegro Design Entry HDL 16.6-p007 (v16-6-112F) 10/10/2012}
"PAGE_NUMBER" = 95;
0"NC";
1"GND\g";
2"GND\g";
3"P3V3\g";
4"P3V3_STBY\g";
5"GND\g";
6"GND\g";
7"GND\g";
8"GND\g";
9"GND\g";
10"GND\g";
11"GND\g";
12"GND\g";
13"P3V3\g";
14"GND\g";
15"GND\g";
16"P3V3\g";
17"GND\g";
18"GND\g";
19"P3V3_STBY\g";
20"FM_SYS_THROTTLE_LVC3";
21"FM_PWRBRK_N";
22"H_CPU0_PROCHOT_G_N";
23"FM_THROTTLE_R_N";
24"FM_THROTTLE_N";
25"FM_SYS_THROTTLE_LVC3";
26"IRQ_CPU1_PROCHOT_G_N";
27"H_CPU1_PROCHOT_G_N";
28"IRQ_CPU0_PROCHOT_G_N";
29"FM_PVCCIN_CPU0_PWR_IN_ALERT_N";
30"IRQ_CPU0_VRHOT";
31"IRQ_CPU1_VRHOT";
32"H_CPU1_PROCHOT_G_N";
33"H_CPU0_MEMABC_MEMHOT_G_N";
34"IRQ_PVCCIN_CPU1_VRHOT_LVC3_N";
35"H_CPU0_MEMDEF_MEMHOT_G_N";
36"H_CPU1_MEMGHJ_MEMHOT_G_N";
37"H_CPU1_MEMKLM_MEMHOT_G_N";
38"FM_PVCCIN_CPU1_PWR_IN_ALERT_N";
39"IRQ_PVCCIN_CPU0_VRHOT_LVC3_N";
40"H_CPU0_PROCHOT_G_N";
%"GND"
"1","(-3100,425)","0","mstr_symbols","I1";
;
HDL_POWER"GND"
BODY_TYPE"PLUMBING"
SIZE"1B"
CDS_LIB"mstr_symbols"
VOLTAGE"0";
"A\NAC"1;
%"GND"
"1","(2150,950)","0","mstr_symbols","I105";
;
HDL_POWER"GND"
ROOM"PROCHOT_MEMHOT_ISO"
BODY_TYPE"PLUMBING"
SIZE"1B"
CDS_LIB"mstr_symbols"
VOLTAGE"0.0V";
"A\NAC"2;
%"RES"
"2","(2150,1800)","0","mstr_discrete","I106";
;
CDS_SEC"1"
PART_NUMBER"G21796-072"
WATTAGE"1/16W"
VALUE"4.75K"
MATERIAL"CHIP"
PACK_TYPE"0402"
TOLERANCE"1%"
LOCATION"R7E7"
ROOM"PROC_SIDEBAND"
CDS_LOCATION"R7E7"
SEC"1"
SEC_TYPE"0402"
CDS_LIB"mstr_discrete";
"A"
$PN"1"3;
"B"
$PN"2"25;
%"P3V3"
"1","(2150,2075)","0","mstr_symbols","I107";
;
HDL_POWER"P3V3"
ROOM"PROCHOT_MEMHOT_ISO"
BODY_TYPE"PLUMBING"
SIZE"1B"
CDS_LIB"mstr_symbols"
VOLTAGE"3.3V";
"G\NAC"3;
%"RES"
"1","(1325,1250)","0","mstr_discrete","I108";
;
CDS_SEC"1"
PACK_TYPE"0402"
PART_NUMBER"G21497-005"
MATERIAL"CHIP"
WATTAGE"1/16W"
TOLERANCE"5%"
VALUE"0.0"
LOCATION"R7E9"
ROOM"PROC_SIDEBAND"
CDS_LOCATION"R7E9"
SEC"1"
BOM_COST"PROC_SIDEBAND"
CDS_LIB"mstr_discrete"
SEC_TYPE"0402";
"B"
$PN"2"23;
"A"
$PN"1"24;
%"FET_N_DUAL"
"5","(2475,4325)","0","mstr_discrete","I111";
;
CDS_SEC"1"
VALUE"NTJD4001N"
MATERIAL"FET"
PART_NUMBER"E40049-001"
LOCATION"Q7E5"
ROOM"HOT_EVENTS"
CDS_LOCATION"Q7E5"
SEC"1"
BOM_COST"PROC_SIDEBAND"
CDS_LIB"mstr_discrete"
SEC_TYPE"SMLF"
PACK_TYPE"SMLF";
"GATE <SIZE -1..0>"
$PN"2"28;
"SOURCE <SIZE-1..0>"
$PN"1"14;
"DRAIN <SIZE -1..0>"
$PN"6"30;
%"FET_N_DUAL"
"5","(2550,2875)","0","mstr_discrete","I112";
;
CDS_SEC"1"
MATERIAL"FET"
VALUE"NTJD4001N"
PART_NUMBER"E40049-001"
LOCATION"Q7E6"
ROOM"HOT_EVENTS"
CDS_LOCATION"Q7E6"
SEC"1"
CDS_LIB"mstr_discrete"
BOM_COST"PROC_SIDEBAND"
SEC_TYPE"SMLF"
PACK_TYPE"SMLF";
"GATE <SIZE -1..0>"
$PN"2"26;
"SOURCE <SIZE-1..0>"
$PN"1"17;
"DRAIN <SIZE -1..0>"
$PN"6"31;
%"FET_N_DUAL"
"5","(-3100,1950)","0","mstr_discrete","I113";
;
CDS_SEC"2"
MATERIAL"FET"
VALUE"NTJD4001N"
PART_NUMBER"E40049-001"
LOCATION"Q2U1"
ROOM"PROC_SIDEBAND"
CDS_LOCATION"Q2U1"
SEC"2"
BOM_COST"PROC_SIDEBAND"
CDS_LIB"mstr_discrete"
SEC_TYPE"SMLF"
PACK_TYPE"SMLF";
"GATE <SIZE -1..0>"
$PN"5"20;
"SOURCE <SIZE-1..0>"
$PN"4"10;
"DRAIN <SIZE -1..0>"
$PN"3"35;
%"P3V3_STBY"
"1","(1125,3675)","0","mstr_symbols","I114";
;
HDL_POWER"P3V3_STBY"
BODY_TYPE"PLUMBING"
CDS_LIB"mstr_symbols"
SIZE"1B"
VOLTAGE"3.3V";
"G\NAC"4;
%"CAP_A"
"1","(1125,3450)","0","dev_discrete","I115";
;
PACK_TYPE"0402V"
LOCATION"C7E4"
VALUE"0.1UF"
VOLTAGE"16V"
TOLERANCE"10%"
MATERIAL"X7R"
PART_NUMBER"A36096-030"
SEC"1"
SEC_TYPE"0402V"
CDS_SEC"1"
CDS_LIB"dev_discrete"
BOM_COST"PROC_SIDEBAND"
CDS_LOCATION"C7E4"
ROOM"PROC_SIDEBAND";
"B"
$PN"2"5;
"A"
$PN"1"4;
%"GND"
"1","(1125,3200)","0","mstr_symbols","I116";
;
HDL_POWER"GND"
BODY_TYPE"PLUMBING"
CDS_LIB"mstr_symbols"
SIZE"1B"
VOLTAGE"0.0V";
"A\NAC"5;
%"TTL1G08"
"1","(1550,4225)","0","mstr_ttl","I117";
;
CDS_SEC"1"
MATERIAL"IC"
PACK_TYPE"SOTLF"
VALUE"NC7SZ08"
LOCATION"U7E2"
POWER_GROUP"VCC=P3V3_STBY;GND=GND;"
PART_NUMBER"D10321-001"
ROOM"CAT_ERR"
CDS_LOCATION"U7E2"
SEC"1"
CDS_LIB"mstr_ttl"
BOM_COST"PROC_SIDEBAND"
SEC_TYPE"SOTLF";
"Y <SIZE-1..0>"
$PN"4"28;
"B <SIZE-1..0>"
$PN"2"39;
"A <SIZE-1..0>"
$PN"1"29;
%"TTL1G08"
"1","(1575,2775)","0","mstr_ttl","I118";
;
CDS_SEC"1"
VALUE"NC7SZ08"
PART_NUMBER"D10321-001"
LOCATION"U7E3"
POWER_GROUP"VCC=P3V3_STBY;GND=GND;"
MATERIAL"IC"
PACK_TYPE"SOTLF"
ROOM"CAT_ERR"
CDS_LOCATION"U7E3"
SEC"1"
SEC_TYPE"SOTLF"
CDS_LIB"mstr_ttl"
BOM_COST"PROC_SIDEBAND";
"Y <SIZE-1..0>"
$PN"4"26;
"B <SIZE-1..0>"
$PN"2"34;
"A <SIZE-1..0>"
$PN"1"38;
%"GND"
"1","(-3100,4250)","0","mstr_symbols","I120";
;
HDL_POWER"GND"
BODY_TYPE"PLUMBING"
SIZE"1B"
CDS_LIB"mstr_symbols"
VOLTAGE"0";
"A\NAC"6;
%"FET_N"
"8","(2150,1350)","0","mstr_discrete","I122";
;
CDS_SEC"1"
$SEC"1"
CDS_LOCATION"Q7E4"
LOCATION"Q7E4"
MATERIAL"FET"
VALUE"2N7002"
PART_NUMBER"C79254-001"
CDS_LIB"mstr_discrete"
ROOM"HOT_SWAP"
PACK_TYPE"SOT23LF";
"GATE"
$PN"1"23;
"DRN"
$PN"3"25;
"SRC"
$PN"2"2;
%"FET_N"
"8","(-3100,4550)","0","mstr_discrete","I123";
;
CDS_SEC"1"
$SEC"1"
CDS_LOCATION"Q7E8"
PART_NUMBER"C79254-001"
VALUE"2N7002"
LOCATION"Q7E8"
MATERIAL"FET"
PACK_TYPE"SOT23LF"
ROOM"HOT_SWAP"
CDS_LIB"mstr_discrete";
"GATE"
$PN"1"20;
"DRN"
$PN"3"21;
"SRC"
$PN"2"6;
%"GND"
"1","(-3100,3675)","0","mstr_symbols","I23";
;
HDL_POWER"GND"
BODY_TYPE"PLUMBING"
CDS_LIB"mstr_symbols"
SIZE"1B"
VOLTAGE"0";
"A\NAC"7;
%"GND"
"1","(-3100,3000)","0","mstr_symbols","I26";
;
HDL_POWER"GND"
BODY_TYPE"PLUMBING"
SIZE"1B"
CDS_LIB"mstr_symbols"
VOLTAGE"0";
"A\NAC"8;
%"GND"
"1","(-3100,2350)","0","mstr_symbols","I27";
;
HDL_POWER"GND"
BODY_TYPE"PLUMBING"
SIZE"1B"
CDS_LIB"mstr_symbols"
VOLTAGE"0";
"A\NAC"9;
%"FET_N_DUAL"
"5","(-3100,2625)","0","mstr_discrete","I28";
;
CDS_SEC"1"
MATERIAL"FET"
VALUE"NTJD4001N"
PART_NUMBER"E40049-001"
LOCATION"Q2U1"
ROOM"PROC_SIDEBAND"
CDS_LOCATION"Q2U1"
SEC"1"
CDS_LIB"mstr_discrete"
SEC_TYPE"SMLF"
BOM_COST"PROC_SIDEBAND"
PACK_TYPE"SMLF";
"GATE <SIZE -1..0>"
$PN"2"20;
"SOURCE <SIZE-1..0>"
$PN"1"9;
"DRAIN <SIZE -1..0>"
$PN"6"33;
%"GND"
"1","(-3100,1675)","0","mstr_symbols","I29";
;
HDL_POWER"GND"
BODY_TYPE"PLUMBING"
SIZE"1B"
CDS_LIB"mstr_symbols"
VOLTAGE"0";
"A\NAC"10;
%"GND"
"1","(-3100,1025)","0","mstr_symbols","I30";
;
HDL_POWER"GND"
BODY_TYPE"PLUMBING"
SIZE"1B"
CDS_LIB"mstr_symbols"
VOLTAGE"0";
"A\NAC"11;
%"FET_N_DUAL"
"5","(-3100,1300)","0","mstr_discrete","I32";
;
CDS_SEC"1"
MATERIAL"FET"
VALUE"NTJD4001N"
PART_NUMBER"E40049-001"
LOCATION"Q4B2"
ROOM"PROC_SIDEBAND"
CDS_LOCATION"Q4B2"
SEC"1"
BOM_COST"PROC_SIDEBAND"
CDS_LIB"mstr_discrete"
SEC_TYPE"SMLF"
PACK_TYPE"SMLF";
"GATE <SIZE -1..0>"
$PN"2"20;
"SOURCE <SIZE-1..0>"
$PN"1"11;
"DRAIN <SIZE -1..0>"
$PN"6"36;
%"FET_N_DUAL"
"5","(-3100,700)","0","mstr_discrete","I33";
;
CDS_SEC"2"
MATERIAL"FET"
VALUE"NTJD4001N"
PART_NUMBER"E40049-001"
LOCATION"Q4B2"
ROOM"PROC_SIDEBAND"
CDS_LOCATION"Q4B2"
SEC"2"
BOM_COST"PROC_SIDEBAND"
CDS_LIB"mstr_discrete"
SEC_TYPE"SMLF"
PACK_TYPE"SMLF";
"GATE <SIZE -1..0>"
$PN"5"20;
"SOURCE <SIZE-1..0>"
$PN"4"1;
"DRAIN <SIZE -1..0>"
$PN"3"37;
%"FET_N_DUAL"
"5","(-3100,3275)","0","mstr_discrete","I51";
;
CDS_SEC"2"
VALUE"NTJD4001N"
MATERIAL"FET"
PART_NUMBER"E40049-001"
LOCATION"Q7E3"
ROOM"PROC_SIDEBAND"
CDS_LOCATION"Q7E3"
SEC"2"
BOM_COST"PROC_SIDEBAND"
CDS_LIB"mstr_discrete"
SEC_TYPE"SMLF"
PACK_TYPE"SMLF";
"GATE <SIZE -1..0>"
$PN"5"20;
"SOURCE <SIZE-1..0>"
$PN"4"8;
"DRAIN <SIZE -1..0>"
$PN"3"32;
%"FET_N_DUAL"
"5","(-3100,3950)","0","mstr_discrete","I52";
;
CDS_SEC"1"
MATERIAL"FET"
VALUE"NTJD4001N"
LOCATION"Q7E3"
PART_NUMBER"E40049-001"
ROOM"PROC_SIDEBAND"
CDS_LOCATION"Q7E3"
SEC"1"
BOM_COST"PROC_SIDEBAND"
CDS_LIB"mstr_discrete"
SEC_TYPE"SMLF"
PACK_TYPE"SMLF";
"GATE <SIZE -1..0>"
$PN"2"20;
"SOURCE <SIZE-1..0>"
$PN"1"7;
"DRAIN <SIZE -1..0>"
$PN"6"22;
%"FET_N_DUAL"
"5","(3050,4725)","0","mstr_discrete","I59";
;
CDS_SEC"2"
MATERIAL"FET"
VALUE"NTJD4001N"
PART_NUMBER"E40049-001"
LOCATION"Q7E5"
ROOM"HOT_EVENTS"
CDS_LOCATION"Q7E5"
SEC"2"
BOM_COST"PROC_SIDEBAND"
CDS_LIB"mstr_discrete"
SEC_TYPE"SMLF"
PACK_TYPE"SMLF";
"GATE <SIZE -1..0>"
$PN"5"30;
"SOURCE <SIZE-1..0>"
$PN"4"12;
"DRAIN <SIZE -1..0>"
$PN"3"40;
%"GND"
"1","(3050,4225)","0","mstr_symbols","I60";
;
HDL_POWER"GND"
ROOM"PROCHOT_MEMHOT_ISO"
BODY_TYPE"PLUMBING"
CDS_LIB"mstr_symbols"
SIZE"1B"
VOLTAGE"0.0V";
"A\NAC"12;
%"P3V3"
"1","(2475,5050)","0","mstr_symbols","I61";
;
HDL_POWER"P3V3"
ROOM"PROCHOT_MEMHOT_ISO"
BODY_TYPE"PLUMBING"
SIZE"1B"
CDS_LIB"mstr_symbols"
VOLTAGE"3.3V";
"G\NAC"13;
%"RES"
"2","(2475,4800)","2","mstr_discrete","I62";
;
PART_NUMBER"G21796-072"
TOLERANCE"1%"
VALUE"4.75K"
LOCATION"R7E10"
WATTAGE"1/16W"
MATERIAL"CHIP"
PACK_TYPE"0402"
ROOM"HOT_EVENTS"
CDS_LOCATION"R7E10"
$SEC"1"
CDS_SEC"1"
BOM_COST"PROC_SIDEBAND"
CDS_LIB"mstr_discrete";
"A"
$PN"1"13;
"B"
$PN"2"30;
%"GND"
"1","(2475,4025)","0","mstr_symbols","I63";
;
HDL_POWER"GND"
ROOM"PROCHOT_MEMHOT_ISO"
BODY_TYPE"PLUMBING"
CDS_LIB"mstr_symbols"
SIZE"1B"
VOLTAGE"0.0V";
"A\NAC"14;
%"FET_N_DUAL"
"5","(3225,3250)","0","mstr_discrete","I69";
;
CDS_SEC"2"
VALUE"NTJD4001N"
MATERIAL"FET"
LOCATION"Q7E6"
PART_NUMBER"E40049-001"
PACK_TYPE"SMLF"
SEC_TYPE"SMLF"
CDS_LIB"mstr_discrete"
BOM_COST"PROC_SIDEBAND"
SEC"2"
CDS_LOCATION"Q7E6"
ROOM"HOT_EVENTS";
"GATE <SIZE -1..0>"
$PN"5"31;
"SOURCE <SIZE-1..0>"
$PN"4"15;
"DRAIN <SIZE -1..0>"
$PN"3"27;
%"GND"
"1","(3225,2825)","0","mstr_symbols","I70";
;
VOLTAGE"0.0V"
CDS_LIB"mstr_symbols"
SIZE"1B"
BODY_TYPE"PLUMBING"
ROOM"PROCHOT_MEMHOT_ISO"
HDL_POWER"GND";
"A\NAC"15;
%"P3V3"
"1","(2550,3600)","0","mstr_symbols","I71";
;
HDL_POWER"P3V3"
ROOM"PROCHOT_MEMHOT_ISO"
BODY_TYPE"PLUMBING"
SIZE"1B"
CDS_LIB"mstr_symbols"
VOLTAGE"3.3V";
"G\NAC"16;
%"RES"
"2","(2550,3375)","2","mstr_discrete","I72";
;
TOLERANCE"1%"
VALUE"4.75K"
LOCATION"R7E11"
PACK_TYPE"0402"
WATTAGE"1/16W"
PART_NUMBER"G21796-072"
MATERIAL"CHIP"
ROOM"HOT_EVENTS"
CDS_LOCATION"R7E11"
$SEC"1"
CDS_SEC"1"
BOM_COST"PROC_SIDEBAND"
CDS_LIB"mstr_discrete";
"A"
$PN"1"16;
"B"
$PN"2"31;
%"GND"
"1","(2550,2575)","0","mstr_symbols","I73";
;
HDL_POWER"GND"
ROOM"PROCHOT_MEMHOT_ISO"
BODY_TYPE"PLUMBING"
SIZE"1B"
CDS_LIB"mstr_symbols"
VOLTAGE"0.0V";
"A\NAC"17;
%"CAP_A"
"1","(700,4775)","0","dev_discrete","I92";
;
MATERIAL"X7R"
PACK_TYPE"0402V"
LOCATION"C7E3"
VALUE"0.1UF"
VOLTAGE"16V"
PART_NUMBER"A36096-030"
TOLERANCE"10%"
SEC"1"
SEC_TYPE"0402V"
CDS_SEC"1"
CDS_LIB"dev_discrete"
BOM_COST"PROC_SIDEBAND"
CDS_LOCATION"C7E3"
ROOM"PROC_SIDEBAND";
"B"
$PN"2"18;
"A"
$PN"1"19;
%"GND"
"1","(700,4525)","0","mstr_symbols","I94";
;
HDL_POWER"GND"
BODY_TYPE"PLUMBING"
SIZE"1B"
CDS_LIB"mstr_symbols"
VOLTAGE"0.0V";
"A\NAC"18;
%"P3V3_STBY"
"1","(700,5000)","0","mstr_symbols","I98";
;
HDL_POWER"P3V3_STBY"
BODY_TYPE"PLUMBING"
SIZE"1B"
CDS_LIB"mstr_symbols"
VOLTAGE"3.3V";
"G\NAC"19;
END.
